# T6G (Grand Teton) — schematic netlist excerpt (pin names and nets, part order shuffled) for the footprints in the layout excerpt that follows; sources: Cadence DE-HDL packaged netlist, KiCad conversion of 04192023_DAF0TMB3IC0_F0TG_MB_C_brd_V02_OCP.brd

PC504_2  Q_CAP  0.1UF 25V 10% X7R  pkg 0402  page 225 : A = PVDD11_S3_P1_VCCS ; B = GND
R228  Q_RES  0 5% CHIP  pkg 0402LF  page 81 : A = PWRGD_PVDD11_S3_P0 ; B = FM_PWRGD_PVDD11_S3_P0

(kicad_pcb
	(version 20260206)
	(generator "pcbnew")
	(generator_version "10.0")
	(general
		(thickness 1.6)
		(legacy_teardrops no)
	)
	(paper "A4")
	(title_block
		(title "04192023_DAF0TMB3IC0_F0TG_MB_C_brd_V02_OCP.brd")
		(comment 1 "Grand Teton / footprints 4732-4733 of 8354")
	)
	(layers
		(0 "F.Cu" signal "TOP")
		(4 "In1.Cu" signal "GND")
		(6 "In2.Cu" signal "IN1")
		(8 "In3.Cu" signal "GND1")
		(10 "In4.Cu" signal "IN2")
		(12 "In5.Cu" signal "GND2")
		(14 "In6.Cu" signal "IN3")
		(16 "In7.Cu" signal "GND3")
		(18 "In8.Cu" signal "VCC")
		(20 "In9.Cu" signal "VCC1")
		(22 "In10.Cu" signal "GND4")
		(24 "In11.Cu" signal "IN4")
		(26 "In12.Cu" signal "GND5")
		(28 "In13.Cu" signal "IN5")
		(30 "In14.Cu" signal "GND6")
		(32 "In15.Cu" signal "IN6")
		(34 "In16.Cu" signal "GND7")
		(2 "B.Cu" signal "BOTTOM")
		(9 "F.Adhes" user "F.Adhesive")
		(11 "B.Adhes" user "B.Adhesive")
		(13 "F.Paste" user "Package Geometry/Pastemask Top")
		(15 "B.Paste" user "Package Geometry/Pastemask Bottom")
		(5 "F.SilkS" user "Ref Des/Silkscreen Top")
		(7 "B.SilkS" user "Ref Des/Silkscreen Bottom")
		(1 "F.Mask" user "Board Geometry/Soldermask Top")
		(3 "B.Mask" user "Board Geometry/Soldermask Bottom")
		(17 "Dwgs.User" user "User.Drawings")
		(19 "Cmts.User" user "User.Comments")
		(21 "Eco1.User" user "User.Eco1")
		(23 "Eco2.User" user "User.Eco2")
		(25 "Edge.Cuts" user "Board Geometry/Outline")
		(27 "Margin" user)
		(31 "F.CrtYd" user "Package Geometry/Place Bound Top")
		(29 "B.CrtYd" user "Package Geometry/Place Bound Bottom")
		(35 "F.Fab" user "Ref Des/Assembly Top")
		(33 "B.Fab" user "Ref Des/Assembly Bottom")
	)
	(footprint ""
		(layer "F.Cu")
		(at 200.939908 -106.513376 180)
		(property "Reference" "R228"
			(at 0 0 180)
			(layer "F.SilkS")
			(hide yes)
			(effects
				(font
					(size 1.27 1.27)
				)
			)
		)
		(property "Value" ""
			(at 0 0 180)
			(layer "F.Fab")
			(effects
				(font
					(size 1.27 1.27)
				)
			)
		)
		(duplicate_pad_numbers_are_jumpers no)
		(fp_line
			(start 0.7874 0.4064)
			(end -0.7874 0.4064)
			(stroke
				(width 0.1524)
				(type default)
			)
			(layer "F.SilkS")
		)
		(fp_line
			(start 0.7874 -0.4064)
			(end 0.7874 0.4064)
			(stroke
				(width 0.1524)
				(type default)
			)
			(layer "F.SilkS")
		)
		(fp_line
			(start -0.7874 0.4064)
			(end -0.7874 -0.4064)
			(stroke
				(width 0.1524)
				(type default)
			)
			(layer "F.SilkS")
		)
		(fp_line
			(start -0.7874 -0.4064)
			(end 0.7874 -0.4064)
			(stroke
				(width 0.1524)
				(type default)
			)
			(layer "F.SilkS")
		)
		(fp_line
			(start 0.67945 0.3048)
			(end 0.120396 0.3048)
			(stroke
				(width 0.1)
				(type default)
			)
			(layer "F.Fab")
		)
		(fp_line
			(start 0.67945 -0.3048)
			(end 0.67945 0.3048)
			(stroke
				(width 0.1)
				(type default)
			)
			(layer "F.Fab")
		)
		(fp_line
			(start 0.12065 -0.2794)
			(end 0.12065 -0.3048)
			(stroke
				(width 0.1)
				(type default)
			)
			(layer "F.Fab")
		)
		(fp_line
			(start 0.12065 -0.3048)
			(end 0.67945 -0.3048)
			(stroke
				(width 0.1)
				(type default)
			)
			(layer "F.Fab")
		)
		(fp_line
			(start 0.120396 0.3048)
			(end 0.120396 0.2794)
			(stroke
				(width 0.1)
				(type default)
			)
			(layer "F.Fab")
		)
		(fp_line
			(start 0.120396 0.2794)
			(end -0.12065 0.2794)
			(stroke
				(width 0.1)
				(type default)
			)
			(layer "F.Fab")
		)
		(fp_line
			(start -0.12065 0.3048)
			(end -0.67945 0.3048)
			(stroke
				(width 0.1)
				(type default)
			)
			(layer "F.Fab")
		)
		(fp_line
			(start -0.12065 0.2794)
			(end -0.12065 0.3048)
			(stroke
				(width 0.1)
				(type default)
			)
			(layer "F.Fab")
		)
		(fp_line
			(start -0.12065 -0.2794)
			(end 0.12065 -0.2794)
			(stroke
				(width 0.1)
				(type default)
			)
			(layer "F.Fab")
		)
		(fp_line
			(start -0.12065 -0.305054)
			(end -0.12065 -0.2794)
			(stroke
				(width 0.1)
				(type default)
			)
			(layer "F.Fab")
		)
		(fp_line
			(start -0.67945 0.3048)
			(end -0.67945 -0.305054)
			(stroke
				(width 0.1)
				(type default)
			)
			(layer "F.Fab")
		)
		(fp_line
			(start -0.67945 -0.305054)
			(end -0.12065 -0.305054)
			(stroke
				(width 0.1)
				(type default)
			)
			(layer "F.Fab")
		)
		(pad "1" smd circle
			(at -0.40005 0 180)
			(size 0 0)
			(layers "F.Cu" "F.Mask" "F.Paste")
			(net "PWRGD_PVDD11_S3_P0")
		)
		(pad "2" smd circle
			(at 0.40005 0 180)
			(size 0 0)
			(layers "F.Cu" "F.Mask" "F.Paste")
			(net "FM_PWRGD_PVDD11_S3_P0")
		)
	)
	(footprint ""
		(layer "F.Cu")
		(at 188.552582 -356.178358 90)
		(property "Reference" "PC504_2"
			(at 0 0 90)
			(layer "F.SilkS")
			(hide yes)
			(effects
				(font
					(size 1.27 1.27)
				)
			)
		)
		(property "Value" ""
			(at 0 0 90)
			(layer "F.Fab")
			(effects
				(font
					(size 1.27 1.27)
				)
			)
		)
		(duplicate_pad_numbers_are_jumpers no)
		(fp_line
			(start 0.7874 -0.4064)
			(end 0.7874 0.4064)
			(stroke
				(width 0.1524)
				(type default)
			)
			(layer "F.SilkS")
		)
		(fp_line
			(start -0.7874 -0.4064)
			(end 0.7874 -0.4064)
			(stroke
				(width 0.1524)
				(type default)
			)
			(layer "F.SilkS")
		)
		(fp_line
			(start 0.7874 0.4064)
			(end -0.7874 0.4064)
			(stroke
				(width 0.1524)
				(type default)
			)
			(layer "F.SilkS")
		)
		(fp_line
			(start -0.7874 0.4064)
			(end -0.7874 -0.4064)
			(stroke
				(width 0.1524)
				(type default)
			)
			(layer "F.SilkS")
		)
		(fp_line
			(start -0.12065 -0.305054)
			(end -0.12065 -0.2794)
			(stroke
				(width 0.1)
				(type default)
			)
			(layer "F.Fab")
		)
		(fp_line
			(start -0.67945 -0.305054)
			(end -0.12065 -0.305054)
			(stroke
				(width 0.1)
				(type default)
			)
			(layer "F.Fab")
		)
		(fp_line
			(start 0.67945 -0.3048)
			(end 0.67945 0.3048)
			(stroke
				(width 0.1)
				(type default)
			)
			(layer "F.Fab")
		)
		(fp_line
			(start 0.12065 -0.3048)
			(end 0.67945 -0.3048)
			(stroke
				(width 0.1)
				(type default)
			)
			(layer "F.Fab")
		)
		(fp_line
			(start 0.12065 -0.2794)
			(end 0.12065 -0.3048)
			(stroke
				(width 0.1)
				(type default)
			)
			(layer "F.Fab")
		)
		(fp_line
			(start -0.12065 -0.2794)
			(end 0.12065 -0.2794)
			(stroke
				(width 0.1)
				(type default)
			)
			(layer "F.Fab")
		)
		(fp_line
			(start 0.120396 0.2794)
			(end -0.12065 0.2794)
			(stroke
				(width 0.1)
				(type default)
			)
			(layer "F.Fab")
		)
		(fp_line
			(start -0.12065 0.2794)
			(end -0.12065 0.3048)
			(stroke
				(width 0.1)
				(type default)
			)
			(layer "F.Fab")
		)
		(fp_line
			(start 0.67945 0.3048)
			(end 0.120396 0.3048)
			(stroke
				(width 0.1)
				(type default)
			)
			(layer "F.Fab")
		)
		(fp_line
			(start 0.120396 0.3048)
			(end 0.120396 0.2794)
			(stroke
				(width 0.1)
				(type default)
			)
			(layer "F.Fab")
		)
		(fp_line
			(start -0.12065 0.3048)
			(end -0.67945 0.3048)
			(stroke
				(width 0.1)
				(type default)
			)
			(layer "F.Fab")
		)
		(fp_line
			(start -0.67945 0.3048)
			(end -0.67945 -0.305054)
			(stroke
				(width 0.1)
				(type default)
			)
			(layer "F.Fab")
		)
		(pad "1" smd circle
			(at -0.40005 0 90)
			(size 0 0)
			(layers "F.Cu" "F.Mask" "F.Paste")
			(net "PVDD11_S3_P1_VCCS")
		)
		(pad "2" smd circle
			(at 0.40005 0 90)
			(size 0 0)
			(layers "F.Cu" "F.Mask" "F.Paste")
			(net "GND")
		)
	)
)
